# SCM (Grand Teton) — schematic netlist excerpt (pin names and nets, part order shuffled) for the footprints in the layout excerpt that follows; sources: Cadence DE-HDL packaged netlist, KiCad conversion of 12092022_DA0F0TMDCD0_F0T_Management_Board_D_brd_V3_OCP.brd

R56  Q_RES  4.7K 1% CHIP  pkg 0402LF  page 13 : A = P3V3_AUX ; B = FM_BIOS_DEBUG_EN_R_N
R233  Q_RES  49.9K 1% CHIP  pkg 0402LF  page 16 : A = GND ; B = A_BMC_ADCREXT0

(kicad_pcb
	(version 20260206)
	(generator "pcbnew")
	(generator_version "10.0")
	(general
		(thickness 1.6)
		(legacy_teardrops no)
	)
	(paper "A4")
	(title_block
		(title "12092022_DA0F0TMDCD0_F0T_Management_Board_D_brd_V3_OCP.brd")
		(comment 1 "Grand Teton / footprints 49-50 of 1440")
	)
	(layers
		(0 "F.Cu" signal "TOP")
		(4 "In1.Cu" signal "GND")
		(6 "In2.Cu" signal "IN1")
		(8 "In3.Cu" signal "GND1")
		(10 "In4.Cu" signal "IN2")
		(12 "In5.Cu" signal "VCC")
		(14 "In6.Cu" signal "VCC1")
		(16 "In7.Cu" signal "IN3")
		(18 "In8.Cu" signal "GND2")
		(20 "In9.Cu" signal "IN4")
		(22 "In10.Cu" signal "GND3")
		(2 "B.Cu" signal "BOTTOM")
		(9 "F.Adhes" user "F.Adhesive")
		(11 "B.Adhes" user "B.Adhesive")
		(13 "F.Paste" user "Package Geometry/Pastemask Top")
		(15 "B.Paste" user "Package Geometry/Pastemask Bottom")
		(5 "F.SilkS" user "Ref Des/Silkscreen Top")
		(7 "B.SilkS" user "Ref Des/Silkscreen Bottom")
		(1 "F.Mask" user "Board Geometry/Soldermask Top")
		(3 "B.Mask" user "Board Geometry/Soldermask Bottom")
		(17 "Dwgs.User" user "User.Drawings")
		(19 "Cmts.User" user "User.Comments")
		(21 "Eco1.User" user "User.Eco1")
		(23 "Eco2.User" user "User.Eco2")
		(25 "Edge.Cuts" user "Board Geometry/Outline")
		(27 "Margin" user)
		(31 "F.CrtYd" user "Package Geometry/Place Bound Top")
		(29 "B.CrtYd" user "Package Geometry/Place Bound Bottom")
		(35 "F.Fab" user "Ref Des/Assembly Top")
		(33 "B.Fab" user "Ref Des/Assembly Bottom")
	)
	(footprint ""
		(layer "F.Cu")
		(at 48.650652 -63.966344 -90)
		(property "Reference" "R233"
			(at 0 0 270)
			(layer "F.SilkS")
			(hide yes)
			(effects
				(font
					(size 1.27 1.27)
				)
			)
		)
		(property "Value" ""
			(at 0 0 270)
			(layer "F.Fab")
			(effects
				(font
					(size 1.27 1.27)
				)
			)
		)
		(duplicate_pad_numbers_are_jumpers no)
		(fp_line
			(start -0.7874 0.4064)
			(end -0.7874 -0.4064)
			(stroke
				(width 0.1524)
				(type default)
			)
			(layer "F.SilkS")
		)
		(fp_line
			(start 0.7874 0.4064)
			(end -0.7874 0.4064)
			(stroke
				(width 0.1524)
				(type default)
			)
			(layer "F.SilkS")
		)
		(fp_line
			(start -0.7874 -0.4064)
			(end 0.7874 -0.4064)
			(stroke
				(width 0.1524)
				(type default)
			)
			(layer "F.SilkS")
		)
		(fp_line
			(start 0.7874 -0.4064)
			(end 0.7874 0.4064)
			(stroke
				(width 0.1524)
				(type default)
			)
			(layer "F.SilkS")
		)
		(fp_line
			(start -0.67945 0.3048)
			(end -0.67945 -0.305054)
			(stroke
				(width 0.1)
				(type default)
			)
			(layer "F.Fab")
		)
		(fp_line
			(start -0.12065 0.3048)
			(end -0.67945 0.3048)
			(stroke
				(width 0.1)
				(type default)
			)
			(layer "F.Fab")
		)
		(fp_line
			(start 0.120396 0.3048)
			(end 0.120396 0.2794)
			(stroke
				(width 0.1)
				(type default)
			)
			(layer "F.Fab")
		)
		(fp_line
			(start 0.67945 0.3048)
			(end 0.120396 0.3048)
			(stroke
				(width 0.1)
				(type default)
			)
			(layer "F.Fab")
		)
		(fp_line
			(start -0.12065 0.2794)
			(end -0.12065 0.3048)
			(stroke
				(width 0.1)
				(type default)
			)
			(layer "F.Fab")
		)
		(fp_line
			(start 0.120396 0.2794)
			(end -0.12065 0.2794)
			(stroke
				(width 0.1)
				(type default)
			)
			(layer "F.Fab")
		)
		(fp_line
			(start -0.12065 -0.2794)
			(end 0.12065 -0.2794)
			(stroke
				(width 0.1)
				(type default)
			)
			(layer "F.Fab")
		)
		(fp_line
			(start 0.12065 -0.2794)
			(end 0.12065 -0.3048)
			(stroke
				(width 0.1)
				(type default)
			)
			(layer "F.Fab")
		)
		(fp_line
			(start 0.12065 -0.3048)
			(end 0.67945 -0.3048)
			(stroke
				(width 0.1)
				(type default)
			)
			(layer "F.Fab")
		)
		(fp_line
			(start 0.67945 -0.3048)
			(end 0.67945 0.3048)
			(stroke
				(width 0.1)
				(type default)
			)
			(layer "F.Fab")
		)
		(fp_line
			(start -0.67945 -0.305054)
			(end -0.12065 -0.305054)
			(stroke
				(width 0.1)
				(type default)
			)
			(layer "F.Fab")
		)
		(fp_line
			(start -0.12065 -0.305054)
			(end -0.12065 -0.2794)
			(stroke
				(width 0.1)
				(type default)
			)
			(layer "F.Fab")
		)
		(pad "1" smd circle
			(at -0.40005 0 270)
			(size 0 0)
			(layers "F.Cu" "F.Mask" "F.Paste")
			(net "GND")
		)
		(pad "2" smd circle
			(at 0.40005 0 270)
			(size 0 0)
			(layers "F.Cu" "F.Mask" "F.Paste")
			(net "A_BMC_ADCREXT0")
		)
	)
	(footprint ""
		(layer "F.Cu")
		(at 42.672 -34.671 90)
		(property "Reference" "R56"
			(at 0 0 90)
			(layer "F.SilkS")
			(hide yes)
			(effects
				(font
					(size 1.27 1.27)
				)
			)
		)
		(property "Value" ""
			(at 0 0 90)
			(layer "F.Fab")
			(effects
				(font
					(size 1.27 1.27)
				)
			)
		)
		(duplicate_pad_numbers_are_jumpers no)
		(fp_line
			(start 0.7874 -0.4064)
			(end 0.7874 0.4064)
			(stroke
				(width 0.1524)
				(type default)
			)
			(layer "F.SilkS")
		)
		(fp_line
			(start -0.7874 -0.4064)
			(end 0.7874 -0.4064)
			(stroke
				(width 0.1524)
				(type default)
			)
			(layer "F.SilkS")
		)
		(fp_line
			(start 0.7874 0.4064)
			(end -0.7874 0.4064)
			(stroke
				(width 0.1524)
				(type default)
			)
			(layer "F.SilkS")
		)
		(fp_line
			(start -0.7874 0.4064)
			(end -0.7874 -0.4064)
			(stroke
				(width 0.1524)
				(type default)
			)
			(layer "F.SilkS")
		)
		(fp_line
			(start -0.12065 -0.305054)
			(end -0.12065 -0.2794)
			(stroke
				(width 0.1)
				(type default)
			)
			(layer "F.Fab")
		)
		(fp_line
			(start -0.67945 -0.305054)
			(end -0.12065 -0.305054)
			(stroke
				(width 0.1)
				(type default)
			)
			(layer "F.Fab")
		)
		(fp_line
			(start 0.67945 -0.3048)
			(end 0.67945 0.3048)
			(stroke
				(width 0.1)
				(type default)
			)
			(layer "F.Fab")
		)
		(fp_line
			(start 0.12065 -0.3048)
			(end 0.67945 -0.3048)
			(stroke
				(width 0.1)
				(type default)
			)
			(layer "F.Fab")
		)
		(fp_line
			(start 0.12065 -0.2794)
			(end 0.12065 -0.3048)
			(stroke
				(width 0.1)
				(type default)
			)
			(layer "F.Fab")
		)
		(fp_line
			(start -0.12065 -0.2794)
			(end 0.12065 -0.2794)
			(stroke
				(width 0.1)
				(type default)
			)
			(layer "F.Fab")
		)
		(fp_line
			(start 0.120396 0.2794)
			(end -0.12065 0.2794)
			(stroke
				(width 0.1)
				(type default)
			)
			(layer "F.Fab")
		)
		(fp_line
			(start -0.12065 0.2794)
			(end -0.12065 0.3048)
			(stroke
				(width 0.1)
				(type default)
			)
			(layer "F.Fab")
		)
		(fp_line
			(start 0.67945 0.3048)
			(end 0.120396 0.3048)
			(stroke
				(width 0.1)
				(type default)
			)
			(layer "F.Fab")
		)
		(fp_line
			(start 0.120396 0.3048)
			(end 0.120396 0.2794)
			(stroke
				(width 0.1)
				(type default)
			)
			(layer "F.Fab")
		)
		(fp_line
			(start -0.12065 0.3048)
			(end -0.67945 0.3048)
			(stroke
				(width 0.1)
				(type default)
			)
			(layer "F.Fab")
		)
		(fp_line
			(start -0.67945 0.3048)
			(end -0.67945 -0.305054)
			(stroke
				(width 0.1)
				(type default)
			)
			(layer "F.Fab")
		)
		(pad "1" smd circle
			(at -0.40005 0 90)
			(size 0 0)
			(layers "F.Cu" "F.Mask" "F.Paste")
			(net "P3V3_AUX")
		)
		(pad "2" smd circle
			(at 0.40005 0 90)
			(size 0 0)
			(layers "F.Cu" "F.Mask" "F.Paste")
			(net "FM_BIOS_DEBUG_EN_R_N")
		)
	)
)
